# BASEBOARD_FAB2 (Tioga Pass) — schematic netlist excerpt (pin names and nets, part order shuffled) for the footprints in the layout excerpt that follows; sources: Cadence DE-HDL packaged netlist, KiCad conversion of Wiwynn_Tioga_Pass_MB.brd

J7G2  CONN8_C77962004  CONN  pkg PIP  page 189
  IO1  = P3V3_STBY_PLD_D
  IO2  = JTAG_TDO_R
  IO3  = JTAG_TDI_R
  IO4  = JTAG_TRST_N
  IO5  = PWRGD_P3V3_STBY
  IO6  = JTAG_TMS_R
  IO7  = GND
  IO8  = JTAG_TCK_R

R8G20  RES  10.0K 1% CHIP  pkg 0402  page 189 : A = P3V3_STBY ; B = JTAG_TMS_R

(kicad_pcb
	(version 20260206)
	(generator "pcbnew")
	(generator_version "10.0")
	(general
		(thickness 1.6)
		(legacy_teardrops no)
	)
	(paper "A4")
	(title_block
		(title "Wiwynn_Tioga_Pass_MB.brd")
		(comment 1 "Tioga Pass / footprints 449-450 of 4770")
	)
	(layers
		(0 "F.Cu" signal "TOP")
		(4 "In1.Cu" signal "L2GND")
		(6 "In2.Cu" signal "L3")
		(8 "In3.Cu" signal "L4GND")
		(10 "In4.Cu" signal "L5")
		(12 "In5.Cu" signal "L6GND")
		(14 "In6.Cu" signal "L7VCC")
		(16 "In7.Cu" signal "L8VCC")
		(18 "In8.Cu" signal "L9GND")
		(20 "In9.Cu" signal "L10")
		(22 "In10.Cu" signal "L11GND")
		(24 "In11.Cu" signal "L12")
		(26 "In12.Cu" signal "L13GND")
		(2 "B.Cu" signal "BOTTOM")
		(9 "F.Adhes" user "F.Adhesive")
		(11 "B.Adhes" user "B.Adhesive")
		(13 "F.Paste" user "Package Geometry/Pastemask Top")
		(15 "B.Paste" user "Package Geometry/Pastemask Bottom")
		(5 "F.SilkS" user "Ref Des/Silkscreen Top")
		(7 "B.SilkS" user "Ref Des/Silkscreen Bottom")
		(1 "F.Mask" user "Board Geometry/Soldermask Top")
		(3 "B.Mask" user "Board Geometry/Soldermask Bottom")
		(17 "Dwgs.User" user "User.Drawings")
		(19 "Cmts.User" user "User.Comments")
		(21 "Eco1.User" user "User.Eco1")
		(23 "Eco2.User" user "User.Eco2")
		(25 "Edge.Cuts" user "Board Geometry/Outline")
		(27 "Margin" user)
		(31 "F.CrtYd" user "Package Geometry/Place Bound Top")
		(29 "B.CrtYd" user "Package Geometry/Place Bound Bottom")
		(35 "F.Fab" user "Ref Des/Assembly Top")
		(33 "B.Fab" user "Ref Des/Assembly Bottom")
	)
	(footprint ""
		(layer "F.Cu")
		(at 382.27 3.81 90)
		(property "Reference" "J7G2"
			(at 3.02133 18.669 0)
			(unlocked yes)
			(layer "F.SilkS")
			(effects
				(font
					(size 0.7874 0.5842)
					(thickness 0.1524)
				)
			)
		)
		(property "Value" ""
			(at 0 0 90)
			(layer "F.Fab")
			(effects
				(font
					(size 1.27 1.27)
				)
			)
		)
		(duplicate_pad_numbers_are_jumpers no)
		(fp_line
			(start 1.2954 -1.27)
			(end 1.2954 19.05)
			(stroke
				(width 0.1524)
				(type default)
			)
			(layer "F.SilkS")
		)
		(fp_line
			(start -1.2954 -1.27)
			(end 1.2954 -1.27)
			(stroke
				(width 0.1524)
				(type default)
			)
			(layer "F.SilkS")
		)
		(fp_line
			(start 1.2954 19.05)
			(end -1.2954 19.05)
			(stroke
				(width 0.1524)
				(type default)
			)
			(layer "F.SilkS")
		)
		(fp_line
			(start -1.2954 19.05)
			(end -1.2954 -1.27)
			(stroke
				(width 0.1524)
				(type default)
			)
			(layer "F.SilkS")
		)
		(fp_poly
			(pts
				(xy 1.070356 -0.705866) (xy 2.340356 -1.213866) (xy 2.340356 -0.197866)
			)
			(stroke
				(width 0)
				(type default)
			)
			(fill yes)
			(layer "F.SilkS")
		)
		(fp_poly
			(pts
				(xy 1.4732 0.0254) (xy 2.7432 -0.4826) (xy 2.7432 0.5334)
			)
			(stroke
				(width 0)
				(type default)
			)
			(fill yes)
			(layer "B.SilkS")
		)
		(fp_poly
			(pts
				(xy -1.2954 19.05) (xy 1.2954 19.05) (xy 1.2954 -1.27) (xy -1.2954 -1.27)
			)
			(stroke
				(width 0)
				(type default)
			)
			(fill no)
			(layer "F.CrtYd")
		)
		(fp_poly
			(pts
				(xy 1.4732 0.0254) (xy 2.7432 -0.4826) (xy 2.7432 0.5334)
			)
			(stroke
				(width 0)
				(type default)
			)
			(fill yes)
			(layer "B.Fab")
		)
		(fp_line
			(start 1.2954 -1.27)
			(end -1.2954 -1.27)
			(stroke
				(width 0.1)
				(type default)
			)
			(layer "F.Fab")
		)
		(fp_line
			(start -1.2954 -1.27)
			(end -1.2954 19.05)
			(stroke
				(width 0.1)
				(type default)
			)
			(layer "F.Fab")
		)
		(fp_line
			(start 1.2954 19.05)
			(end 1.2954 -1.27)
			(stroke
				(width 0.1)
				(type default)
			)
			(layer "F.Fab")
		)
		(fp_line
			(start -1.2954 19.05)
			(end 1.2954 19.05)
			(stroke
				(width 0.1)
				(type default)
			)
			(layer "F.Fab")
		)
		(fp_poly
			(pts
				(xy 1.4732 0.0254) (xy 2.7432 -0.4826) (xy 2.7432 0.5334)
			)
			(stroke
				(width 0)
				(type default)
			)
			(fill yes)
			(layer "F.Fab")
		)
		(fp_text user "8"
			(at 1.76911 19.26844 0)
			(unlocked yes)
			(layer "F.SilkS")
			(effects
				(font
					(size 0.7874 0.5842)
					(thickness 0.1524)
				)
			)
		)
		(fp_text user "8"
			(at 1.8288 17.85747 90)
			(unlocked yes)
			(layer "B.SilkS")
			(effects
				(font
					(size 0.7874 0.5842)
					(thickness 0.1524)
				)
			)
		)
		(fp_text user "8"
			(at 1.8288 17.85747 90)
			(unlocked yes)
			(layer "B.Fab")
			(effects
				(font
					(size 0.7874 0.5842)
					(thickness 0.1524)
				)
			)
		)
		(fp_text user "8"
			(at 0.218694 -1.651 0)
			(unlocked yes)
			(layer "F.Fab")
			(effects
				(font
					(size 0.7874 0.5842)
					(thickness 0.1524)
				)
			)
		)
		(pad "1" thru_hole rect
			(at 0 0 90)
			(size 1.6256 1.6256)
			(drill 1.2446)
			(layers "*.Cu" "*.Mask")
			(remove_unused_layers no)
			(net "P3V3_STBY_PLD_D")
			(clearance 0.127)
			(thermal_gap 0.127)
			(padstack
				(mode front_inner_back)
				(layer "Inner"
					(shape circle)
					(size 1.6256 1.6256)
					(clearance 0.127)
				)
				(layer "B.Cu"
					(shape rect)
					(size 1.6256 1.6256)
					(clearance 0.127)
				)
			)
		)
		(pad "2" thru_hole circle
			(at 0 2.54 90)
			(size 1.6256 1.6256)
			(drill 1.2446)
			(layers "*.Cu" "*.Mask")
			(remove_unused_layers no)
			(net "JTAG_TDO_R")
			(clearance 0.127)
			(thermal_gap 0.127)
		)
		(pad "3" thru_hole circle
			(at 0 5.08 90)
			(size 1.6256 1.6256)
			(drill 1.2446)
			(layers "*.Cu" "*.Mask")
			(remove_unused_layers no)
			(net "JTAG_TDI_R")
			(clearance 0.127)
			(thermal_gap 0.127)
		)
		(pad "4" thru_hole circle
			(at 0 7.62 90)
			(size 1.6256 1.6256)
			(drill 1.2446)
			(layers "*.Cu" "*.Mask")
			(remove_unused_layers no)
			(net "JTAG_TRST_N")
			(clearance 0.127)
			(thermal_gap 0.127)
		)
		(pad "5" thru_hole circle
			(at 0 10.16 90)
			(size 1.6256 1.6256)
			(drill 1.2446)
			(layers "*.Cu" "*.Mask")
			(remove_unused_layers no)
			(net "PWRGD_P3V3_STBY")
			(clearance 0.127)
			(thermal_gap 0.127)
		)
		(pad "6" thru_hole circle
			(at 0 12.7 90)
			(size 1.6256 1.6256)
			(drill 1.2446)
			(layers "*.Cu" "*.Mask")
			(remove_unused_layers no)
			(net "JTAG_TMS_R")
			(clearance 0.127)
			(thermal_gap 0.127)
		)
		(pad "7" thru_hole circle
			(at 0 15.24 90)
			(size 1.6256 1.6256)
			(drill 1.2446)
			(layers "*.Cu" "*.Mask")
			(remove_unused_layers no)
			(net "GND")
			(clearance 0.127)
			(thermal_gap 0.127)
		)
		(pad "8" thru_hole circle
			(at 0 17.78 90)
			(size 1.6256 1.6256)
			(drill 1.2446)
			(layers "*.Cu" "*.Mask")
			(remove_unused_layers no)
			(net "JTAG_TCK_R")
			(clearance 0.127)
			(thermal_gap 0.127)
		)
	)
	(footprint ""
		(layer "F.Cu")
		(at 393.1412 1.5748 90)
		(property "Reference" "R8G20"
			(at 0 0 90)
			(layer "F.SilkS")
			(hide yes)
			(effects
				(font
					(size 1.27 1.27)
				)
			)
		)
		(property "Value" ""
			(at 0 0 90)
			(layer "F.Fab")
			(effects
				(font
					(size 1.27 1.27)
				)
			)
		)
		(duplicate_pad_numbers_are_jumpers no)
		(fp_poly
			(pts
				(xy -0.2794 -0.1016) (xy 0.2794 -0.1016) (xy 0.2794 0.9906) (xy -0.2794 0.9906)
			)
			(stroke
				(width 0)
				(type default)
			)
			(fill no)
			(layer "F.CrtYd")
		)
		(fp_line
			(start 0.2794 -0.1016)
			(end -0.2794 -0.1016)
			(stroke
				(width 0.1)
				(type default)
			)
			(layer "F.Fab")
		)
		(fp_line
			(start -0.2794 -0.1016)
			(end -0.2794 0.9906)
			(stroke
				(width 0.1)
				(type default)
			)
			(layer "F.Fab")
		)
		(fp_line
			(start 0.2794 0.9906)
			(end 0.2794 -0.1016)
			(stroke
				(width 0.1)
				(type default)
			)
			(layer "F.Fab")
		)
		(fp_line
			(start -0.2794 0.9906)
			(end 0.2794 0.9906)
			(stroke
				(width 0.1)
				(type default)
			)
			(layer "F.Fab")
		)
		(pad "1" smd rect
			(at 0 0 90)
			(size 0.508 0.508)
			(layers "F.Cu" "F.Mask" "F.Paste")
			(net "P3V3_STBY")
		)
		(pad "2" smd rect
			(at 0 0.889 90)
			(size 0.508 0.508)
			(layers "F.Cu" "F.Mask" "F.Paste")
			(net "JTAG_TMS_R")
		)
		(zone
			(layer "F.Cu")
			(hatch none 0.5)
			(connect_pads
				(clearance 0)
			)
			(min_thickness 0.25)
			(keepout
				(tracks allowed)
				(vias not_allowed)
				(pads allowed)
				(copperpour not_allowed)
				(footprints allowed)
			)
			(placement
				(enabled no)
				(sheetname "")
			)
			(fill
				(thermal_gap 0.5)
				(thermal_bridge_width 0.5)
				(island_removal_mode 0)
			)
			(polygon
				(pts
					(xy 393.3952 1.8288) (xy 393.3952 1.3208) (xy 393.7762 1.3208) (xy 393.7762 1.8288)
				)
			)
		)
		(zone
			(layer "F.Cu")
			(hatch none 0.5)
			(connect_pads
				(clearance 0)
			)
			(min_thickness 0.25)
			(keepout
				(tracks not_allowed)
				(vias allowed)
				(pads allowed)
				(copperpour not_allowed)
				(footprints allowed)
			)
			(placement
				(enabled no)
				(sheetname "")
			)
			(fill
				(thermal_gap 0.5)
				(thermal_bridge_width 0.5)
				(island_removal_mode 0)
			)
			(polygon
				(pts
					(xy 393.7762 1.8288) (xy 393.7762 1.3208) (xy 393.3952 1.3208) (xy 393.3952 1.8288)
				)
			)
		)
	)
)
